# S9S_MB_2U (Grand Teton) — schematic netlist excerpt (pin names and nets, part order shuffled) for the footprints in the layout excerpt that follows; sources: Cadence DE-HDL packaged netlist, KiCad conversion of 03242023_DA0F0TMBIJ0_F0T_Motherboard_J_brd_V01_OCP.brd

R4149  Q_RES  33.2 1% CHIP  pkg 0402LF  page 241 : A = SMB_1_PLD_3V3AUX_SCL ; B = SMB_1_PLD_3V3AUX_SCL_R1
R1841  Q_RES  10K 1% CHIP  pkg 0402LF  page 218 : A = P3V3_AUX ; B = FM_CPU_RMCA_CATERR_LVT3_R_N

(kicad_pcb
	(version 20260206)
	(generator "pcbnew")
	(generator_version "10.0")
	(general
		(thickness 1.6)
		(legacy_teardrops no)
	)
	(paper "A4")
	(title_block
		(title "03242023_DA0F0TMBIJ0_F0T_Motherboard_J_brd_V01_OCP.brd")
		(comment 1 "Grand Teton / footprints 3710-3711 of 6105")
	)
	(layers
		(0 "F.Cu" signal "TOP")
		(4 "In1.Cu" signal "GND")
		(6 "In2.Cu" signal "IN1")
		(8 "In3.Cu" signal "GND1")
		(10 "In4.Cu" signal "IN2")
		(12 "In5.Cu" signal "GND2")
		(14 "In6.Cu" signal "IN3")
		(16 "In7.Cu" signal "GND3")
		(18 "In8.Cu" signal "VCC")
		(20 "In9.Cu" signal "VCC1")
		(22 "In10.Cu" signal "GND4")
		(24 "In11.Cu" signal "IN4")
		(26 "In12.Cu" signal "GND5")
		(28 "In13.Cu" signal "IN5")
		(30 "In14.Cu" signal "GND6")
		(32 "In15.Cu" signal "IN6")
		(34 "In16.Cu" signal "GND7")
		(2 "B.Cu" signal "BOTTOM")
		(9 "F.Adhes" user "F.Adhesive")
		(11 "B.Adhes" user "B.Adhesive")
		(13 "F.Paste" user "Package Geometry/Pastemask Top")
		(15 "B.Paste" user "Package Geometry/Pastemask Bottom")
		(5 "F.SilkS" user "Ref Des/Silkscreen Top")
		(7 "B.SilkS" user "Ref Des/Silkscreen Bottom")
		(1 "F.Mask" user "Board Geometry/Soldermask Top")
		(3 "B.Mask" user "Board Geometry/Soldermask Bottom")
		(17 "Dwgs.User" user "User.Drawings")
		(19 "Cmts.User" user "User.Comments")
		(21 "Eco1.User" user "User.Eco1")
		(23 "Eco2.User" user "User.Eco2")
		(25 "Edge.Cuts" user "Board Geometry/Outline")
		(27 "Margin" user)
		(31 "F.CrtYd" user "Package Geometry/Place Bound Top")
		(29 "B.CrtYd" user "Package Geometry/Place Bound Bottom")
		(35 "F.Fab" user "Ref Des/Assembly Top")
		(33 "B.Fab" user "Ref Des/Assembly Bottom")
	)
	(footprint ""
		(layer "F.Cu")
		(at 200.58888 -108.422948 90)
		(property "Reference" "R1841"
			(at 0 0 90)
			(layer "F.SilkS")
			(hide yes)
			(effects
				(font
					(size 1.27 1.27)
				)
			)
		)
		(property "Value" ""
			(at 0 0 90)
			(layer "F.Fab")
			(effects
				(font
					(size 1.27 1.27)
				)
			)
		)
		(duplicate_pad_numbers_are_jumpers no)
		(fp_line
			(start 0.7874 -0.4064)
			(end 0.7874 0.4064)
			(stroke
				(width 0.1524)
				(type default)
			)
			(layer "F.SilkS")
		)
		(fp_line
			(start -0.7874 -0.4064)
			(end 0.7874 -0.4064)
			(stroke
				(width 0.1524)
				(type default)
			)
			(layer "F.SilkS")
		)
		(fp_line
			(start 0.7874 0.4064)
			(end -0.7874 0.4064)
			(stroke
				(width 0.1524)
				(type default)
			)
			(layer "F.SilkS")
		)
		(fp_line
			(start -0.7874 0.4064)
			(end -0.7874 -0.4064)
			(stroke
				(width 0.1524)
				(type default)
			)
			(layer "F.SilkS")
		)
		(fp_line
			(start -0.12065 -0.305054)
			(end -0.12065 -0.2794)
			(stroke
				(width 0.1)
				(type default)
			)
			(layer "F.Fab")
		)
		(fp_line
			(start -0.67945 -0.305054)
			(end -0.12065 -0.305054)
			(stroke
				(width 0.1)
				(type default)
			)
			(layer "F.Fab")
		)
		(fp_line
			(start 0.67945 -0.3048)
			(end 0.67945 0.3048)
			(stroke
				(width 0.1)
				(type default)
			)
			(layer "F.Fab")
		)
		(fp_line
			(start 0.12065 -0.3048)
			(end 0.67945 -0.3048)
			(stroke
				(width 0.1)
				(type default)
			)
			(layer "F.Fab")
		)
		(fp_line
			(start 0.12065 -0.2794)
			(end 0.12065 -0.3048)
			(stroke
				(width 0.1)
				(type default)
			)
			(layer "F.Fab")
		)
		(fp_line
			(start -0.12065 -0.2794)
			(end 0.12065 -0.2794)
			(stroke
				(width 0.1)
				(type default)
			)
			(layer "F.Fab")
		)
		(fp_line
			(start 0.120396 0.2794)
			(end -0.12065 0.2794)
			(stroke
				(width 0.1)
				(type default)
			)
			(layer "F.Fab")
		)
		(fp_line
			(start -0.12065 0.2794)
			(end -0.12065 0.3048)
			(stroke
				(width 0.1)
				(type default)
			)
			(layer "F.Fab")
		)
		(fp_line
			(start 0.67945 0.3048)
			(end 0.120396 0.3048)
			(stroke
				(width 0.1)
				(type default)
			)
			(layer "F.Fab")
		)
		(fp_line
			(start 0.120396 0.3048)
			(end 0.120396 0.2794)
			(stroke
				(width 0.1)
				(type default)
			)
			(layer "F.Fab")
		)
		(fp_line
			(start -0.12065 0.3048)
			(end -0.67945 0.3048)
			(stroke
				(width 0.1)
				(type default)
			)
			(layer "F.Fab")
		)
		(fp_line
			(start -0.67945 0.3048)
			(end -0.67945 -0.305054)
			(stroke
				(width 0.1)
				(type default)
			)
			(layer "F.Fab")
		)
		(pad "1" smd circle
			(at -0.40005 0 90)
			(size 0 0)
			(layers "F.Cu" "F.Mask" "F.Paste")
			(net "P3V3_AUX")
		)
		(pad "2" smd circle
			(at 0.40005 0 90)
			(size 0 0)
			(layers "F.Cu" "F.Mask" "F.Paste")
			(net "FM_CPU_RMCA_CATERR_LVT3_R_N")
		)
	)
	(footprint ""
		(layer "F.Cu")
		(at 162.563302 -23.38959)
		(property "Reference" "R4149"
			(at 0 0 0)
			(layer "F.SilkS")
			(hide yes)
			(effects
				(font
					(size 1.27 1.27)
				)
			)
		)
		(property "Value" ""
			(at 0 0 0)
			(layer "F.Fab")
			(effects
				(font
					(size 1.27 1.27)
				)
			)
		)
		(duplicate_pad_numbers_are_jumpers no)
		(fp_line
			(start -0.7874 -0.4064)
			(end 0.7874 -0.4064)
			(stroke
				(width 0.1524)
				(type default)
			)
			(layer "F.SilkS")
		)
		(fp_line
			(start -0.7874 0.4064)
			(end -0.7874 -0.4064)
			(stroke
				(width 0.1524)
				(type default)
			)
			(layer "F.SilkS")
		)
		(fp_line
			(start 0.7874 -0.4064)
			(end 0.7874 0.4064)
			(stroke
				(width 0.1524)
				(type default)
			)
			(layer "F.SilkS")
		)
		(fp_line
			(start 0.7874 0.4064)
			(end -0.7874 0.4064)
			(stroke
				(width 0.1524)
				(type default)
			)
			(layer "F.SilkS")
		)
		(fp_line
			(start -0.67945 -0.305054)
			(end -0.12065 -0.305054)
			(stroke
				(width 0.1)
				(type default)
			)
			(layer "F.Fab")
		)
		(fp_line
			(start -0.67945 0.3048)
			(end -0.67945 -0.305054)
			(stroke
				(width 0.1)
				(type default)
			)
			(layer "F.Fab")
		)
		(fp_line
			(start -0.12065 -0.305054)
			(end -0.12065 -0.2794)
			(stroke
				(width 0.1)
				(type default)
			)
			(layer "F.Fab")
		)
		(fp_line
			(start -0.12065 -0.2794)
			(end 0.12065 -0.2794)
			(stroke
				(width 0.1)
				(type default)
			)
			(layer "F.Fab")
		)
		(fp_line
			(start -0.12065 0.2794)
			(end -0.12065 0.3048)
			(stroke
				(width 0.1)
				(type default)
			)
			(layer "F.Fab")
		)
		(fp_line
			(start -0.12065 0.3048)
			(end -0.67945 0.3048)
			(stroke
				(width 0.1)
				(type default)
			)
			(layer "F.Fab")
		)
		(fp_line
			(start 0.120396 0.2794)
			(end -0.12065 0.2794)
			(stroke
				(width 0.1)
				(type default)
			)
			(layer "F.Fab")
		)
		(fp_line
			(start 0.120396 0.3048)
			(end 0.120396 0.2794)
			(stroke
				(width 0.1)
				(type default)
			)
			(layer "F.Fab")
		)
		(fp_line
			(start 0.12065 -0.3048)
			(end 0.67945 -0.3048)
			(stroke
				(width 0.1)
				(type default)
			)
			(layer "F.Fab")
		)
		(fp_line
			(start 0.12065 -0.2794)
			(end 0.12065 -0.3048)
			(stroke
				(width 0.1)
				(type default)
			)
			(layer "F.Fab")
		)
		(fp_line
			(start 0.67945 -0.3048)
			(end 0.67945 0.3048)
			(stroke
				(width 0.1)
				(type default)
			)
			(layer "F.Fab")
		)
		(fp_line
			(start 0.67945 0.3048)
			(end 0.120396 0.3048)
			(stroke
				(width 0.1)
				(type default)
			)
			(layer "F.Fab")
		)
		(pad "1" smd circle
			(at -0.40005 0)
			(size 0 0)
			(layers "F.Cu" "F.Mask" "F.Paste")
			(net "SMB_1_PLD_3V3AUX_SCL")
		)
		(pad "2" smd circle
			(at 0.40005 0)
			(size 0 0)
			(layers "F.Cu" "F.Mask" "F.Paste")
			(net "SMB_1_PLD_3V3AUX_SCL_R1")
		)
	)
)
